#ISCELL
  logical_power cad_note *
  *
#ISCELL
  pure_quanta quanta_title_block_c *
  *
#CELL
  pure_quanta q_res *
  page173_i1
#ISCELL
  standard offpage *
  page173_i10
#ISCELL
  standard offpage *
  page173_i100
#ISCELL
  standard offpage *
  page173_i101
#ISCELL
  standard offpage *
  page173_i102
#ISCELL
  standard offpage *
  page173_i103
#ISCELL
  standard offpage *
  page173_i104
#ISCELL
  standard offpage *
  page173_i105
#ISCELL
  standard offpage *
  page173_i106
#ISCELL
  standard offpage *
  page173_i107
#ISCELL
  standard offpage *
  page173_i108
#ISCELL
  standard offpage *
  page173_i109
#ISCELL
  standard offpage *
  page173_i11
#CELL
  pure_quanta emmitsburg_rev0p9 *
  page173_i110
#ISCELL
  standard offpage *
  page173_i12
#ISCELL
  standard offpage *
  page173_i13
#ISCELL
  standard offpage *
  page173_i14
#ISCELL
  standard offpage *
  page173_i15
#ISCELL
  standard offpage *
  page173_i16
#ISCELL
  standard offpage *
  page173_i17
#ISCELL
  standard offpage *
  page173_i18
#ISCELL
  standard offpage *
  page173_i19
#ISCELL
  standard offpage *
  page173_i2
#ISCELL
  standard offpage *
  page173_i20
#ISCELL
  standard offpage *
  page173_i21
#ISCELL
  standard offpage *
  page173_i22
#ISCELL
  standard offpage *
  page173_i23
#ISCELL
  standard offpage *
  page173_i24
#ISCELL
  standard offpage *
  page173_i25
#ISCELL
  standard tap *
  page173_i26
#ISCELL
  standard tap *
  page173_i27
#ISCELL
  standard tap *
  page173_i28
#ISCELL
  standard offpage *
  page173_i29
#ISCELL
  standard offpage *
  page173_i3
#ISCELL
  standard offpage *
  page173_i30
#ISCELL
  standard tap *
  page173_i31
#ISCELL
  standard tap *
  page173_i32
#ISCELL
  standard tap *
  page173_i33
#ISCELL
  standard tap *
  page173_i34
#ISCELL
  standard tap *
  page173_i35
#ISCELL
  standard tap *
  page173_i36
#ISCELL
  standard tap *
  page173_i37
#ISCELL
  standard tap *
  page173_i38
#ISCELL
  standard tap *
  page173_i39
#ISCELL
  standard offpage *
  page173_i4
#ISCELL
  standard tap *
  page173_i40
#ISCELL
  standard tap *
  page173_i41
#ISCELL
  standard tap *
  page173_i42
#ISCELL
  standard tap *
  page173_i43
#ISCELL
  standard tap *
  page173_i44
#ISCELL
  standard tap *
  page173_i45
#ISCELL
  standard tap *
  page173_i46
#ISCELL
  standard tap *
  page173_i47
#ISCELL
  standard tap *
  page173_i48
#ISCELL
  standard tap *
  page173_i49
#ISCELL
  standard offpage *
  page173_i5
#ISCELL
  standard tap *
  page173_i50
#ISCELL
  standard tap *
  page173_i51
#ISCELL
  standard tap *
  page173_i52
#ISCELL
  standard tap *
  page173_i53
#ISCELL
  standard tap *
  page173_i54
#ISCELL
  standard tap *
  page173_i55
#ISCELL
  standard tap *
  page173_i56
#ISCELL
  standard tap *
  page173_i57
#ISCELL
  standard tap *
  page173_i58
#ISCELL
  standard tap *
  page173_i59
#ISCELL
  standard offpage *
  page173_i6
#CELL
  pure_quanta q_cap_diffbus *
  page173_i60
#CELL
  pure_quanta q_cap_diffbus *
  page173_i61
#CELL
  pure_quanta q_cap_diffbus *
  page173_i62
#CELL
  pure_quanta q_cap_diffbus *
  page173_i63
#CELL
  pure_quanta q_cap_diffbus *
  page173_i64
#CELL
  pure_quanta q_cap_diffbus *
  page173_i65
#CELL
  pure_quanta q_cap_diffbus *
  page173_i66
#CELL
  pure_quanta q_cap_diffbus *
  page173_i67
#CELL
  pure_quanta q_cap_diffbus *
  page173_i68
#CELL
  pure_quanta q_cap_diffbus *
  page173_i69
#ISCELL
  standard offpage *
  page173_i7
#CELL
  pure_quanta q_cap_diffbus *
  page173_i70
#CELL
  pure_quanta q_cap_diffbus *
  page173_i71
#CELL
  pure_quanta q_cap_diffbus *
  page173_i72
#CELL
  pure_quanta q_cap_diffbus *
  page173_i73
#CELL
  pure_quanta q_cap_diffbus *
  page173_i74
#CELL
  pure_quanta q_cap_diffbus *
  page173_i75
#CELL
  pure_quanta q_cap_diffbus *
  page173_i76
#CELL
  pure_quanta q_cap_diffbus *
  page173_i77
#CELL
  pure_quanta q_cap *
  page173_i78
#CELL
  pure_quanta q_cap_diffbus *
  page173_i79
#ISCELL
  standard offpage *
  page173_i8
#CELL
  pure_quanta q_cap *
  page173_i80
#CELL
  pure_quanta q_cap_diffbus *
  page173_i81
#CELL
  pure_quanta q_cap_diffbus *
  page173_i82
#CELL
  pure_quanta q_cap_diffbus *
  page173_i83
#ISCELL
  standard offpage *
  page173_i84
#ISCELL
  standard offpage *
  page173_i85
#ISCELL
  standard offpage *
  page173_i86
#ISCELL
  standard offpage *
  page173_i87
#ISCELL
  standard offpage *
  page173_i88
#ISCELL
  standard offpage *
  page173_i89
#ISCELL
  standard offpage *
  page173_i9
#ISCELL
  standard offpage *
  page173_i90
#ISCELL
  standard offpage *
  page173_i91
#ISCELL
  standard offpage *
  page173_i92
#ISCELL
  standard offpage *
  page173_i93
#ISCELL
  standard offpage *
  page173_i94
#ISCELL
  standard offpage *
  page173_i95
#ISCELL
  standard offpage *
  page173_i96
#ISCELL
  standard offpage *
  page173_i97
#ISCELL
  standard offpage *
  page173_i98
#ISCELL
  standard offpage *
  page173_i99
